# S9S_MB_2U (Grand Teton) — schematic netlist excerpt (pin names and nets, part order shuffled) for the footprints in the layout excerpt that follows; sources: Cadence DE-HDL packaged netlist, KiCad conversion of 03242023_DA0F0TMBIJ0_F0T_Motherboard_J_brd_V01_OCP.brd

C264  Q_CAP  10UF 6.3V 20% X6S  pkg C0402  page 77 : A = PVCCIN_CPU1 ; B = GND
PC2183  Q_CAP  220PF 50V 10% EMPTY  pkg 0402  page 302 : A = HSC_ON ; B = AGND_HSC

(kicad_pcb
	(version 20260206)
	(generator "pcbnew")
	(generator_version "10.0")
	(general
		(thickness 1.6)
		(legacy_teardrops no)
	)
	(paper "A4")
	(title_block
		(title "03242023_DA0F0TMBIJ0_F0T_Motherboard_J_brd_V01_OCP.brd")
		(comment 1 "Grand Teton / footprints 1478-1479 of 6105")
	)
	(layers
		(0 "F.Cu" signal "TOP")
		(4 "In1.Cu" signal "GND")
		(6 "In2.Cu" signal "IN1")
		(8 "In3.Cu" signal "GND1")
		(10 "In4.Cu" signal "IN2")
		(12 "In5.Cu" signal "GND2")
		(14 "In6.Cu" signal "IN3")
		(16 "In7.Cu" signal "GND3")
		(18 "In8.Cu" signal "VCC")
		(20 "In9.Cu" signal "VCC1")
		(22 "In10.Cu" signal "GND4")
		(24 "In11.Cu" signal "IN4")
		(26 "In12.Cu" signal "GND5")
		(28 "In13.Cu" signal "IN5")
		(30 "In14.Cu" signal "GND6")
		(32 "In15.Cu" signal "IN6")
		(34 "In16.Cu" signal "GND7")
		(2 "B.Cu" signal "BOTTOM")
		(9 "F.Adhes" user "F.Adhesive")
		(11 "B.Adhes" user "B.Adhesive")
		(13 "F.Paste" user "Package Geometry/Pastemask Top")
		(15 "B.Paste" user "Package Geometry/Pastemask Bottom")
		(5 "F.SilkS" user "Ref Des/Silkscreen Top")
		(7 "B.SilkS" user "Ref Des/Silkscreen Bottom")
		(1 "F.Mask" user "Board Geometry/Soldermask Top")
		(3 "B.Mask" user "Board Geometry/Soldermask Bottom")
		(17 "Dwgs.User" user "User.Drawings")
		(19 "Cmts.User" user "User.Comments")
		(21 "Eco1.User" user "User.Eco1")
		(23 "Eco2.User" user "User.Eco2")
		(25 "Edge.Cuts" user "Board Geometry/Outline")
		(27 "Margin" user)
		(31 "F.CrtYd" user "Package Geometry/Place Bound Top")
		(29 "B.CrtYd" user "Package Geometry/Place Bound Bottom")
		(35 "F.Fab" user "Ref Des/Assembly Top")
		(33 "B.Fab" user "Ref Des/Assembly Bottom")
	)
	(footprint ""
		(layer "F.Cu")
		(at 118.542816 -245.634256 -90)
		(property "Reference" "C264"
			(at 0 0 270)
			(layer "F.SilkS")
			(hide yes)
			(effects
				(font
					(size 1.27 1.27)
				)
			)
		)
		(property "Value" ""
			(at 0 0 270)
			(layer "F.Fab")
			(effects
				(font
					(size 1.27 1.27)
				)
			)
		)
		(duplicate_pad_numbers_are_jumpers no)
		(fp_line
			(start -0.7874 0.4064)
			(end -0.7874 -0.4064)
			(stroke
				(width 0.1524)
				(type default)
			)
			(layer "F.SilkS")
		)
		(fp_line
			(start 0.7874 0.4064)
			(end -0.7874 0.4064)
			(stroke
				(width 0.1524)
				(type default)
			)
			(layer "F.SilkS")
		)
		(fp_line
			(start -0.7874 -0.4064)
			(end 0.7874 -0.4064)
			(stroke
				(width 0.1524)
				(type default)
			)
			(layer "F.SilkS")
		)
		(fp_line
			(start 0.7874 -0.4064)
			(end 0.7874 0.4064)
			(stroke
				(width 0.1524)
				(type default)
			)
			(layer "F.SilkS")
		)
		(fp_line
			(start -0.67945 0.3048)
			(end -0.67945 -0.305054)
			(stroke
				(width 0.1)
				(type default)
			)
			(layer "F.Fab")
		)
		(fp_line
			(start -0.12065 0.3048)
			(end -0.67945 0.3048)
			(stroke
				(width 0.1)
				(type default)
			)
			(layer "F.Fab")
		)
		(fp_line
			(start 0.120396 0.3048)
			(end 0.120396 0.2794)
			(stroke
				(width 0.1)
				(type default)
			)
			(layer "F.Fab")
		)
		(fp_line
			(start 0.67945 0.3048)
			(end 0.120396 0.3048)
			(stroke
				(width 0.1)
				(type default)
			)
			(layer "F.Fab")
		)
		(fp_line
			(start -0.12065 0.2794)
			(end -0.12065 0.3048)
			(stroke
				(width 0.1)
				(type default)
			)
			(layer "F.Fab")
		)
		(fp_line
			(start 0.120396 0.2794)
			(end -0.12065 0.2794)
			(stroke
				(width 0.1)
				(type default)
			)
			(layer "F.Fab")
		)
		(fp_line
			(start -0.12065 -0.2794)
			(end 0.12065 -0.2794)
			(stroke
				(width 0.1)
				(type default)
			)
			(layer "F.Fab")
		)
		(fp_line
			(start 0.12065 -0.2794)
			(end 0.12065 -0.3048)
			(stroke
				(width 0.1)
				(type default)
			)
			(layer "F.Fab")
		)
		(fp_line
			(start 0.12065 -0.3048)
			(end 0.67945 -0.3048)
			(stroke
				(width 0.1)
				(type default)
			)
			(layer "F.Fab")
		)
		(fp_line
			(start 0.67945 -0.3048)
			(end 0.67945 0.3048)
			(stroke
				(width 0.1)
				(type default)
			)
			(layer "F.Fab")
		)
		(fp_line
			(start -0.67945 -0.305054)
			(end -0.12065 -0.305054)
			(stroke
				(width 0.1)
				(type default)
			)
			(layer "F.Fab")
		)
		(fp_line
			(start -0.12065 -0.305054)
			(end -0.12065 -0.2794)
			(stroke
				(width 0.1)
				(type default)
			)
			(layer "F.Fab")
		)
		(pad "1" smd circle
			(at -0.40005 0 270)
			(size 0 0)
			(layers "F.Cu" "F.Mask" "F.Paste")
			(net "PVCCIN_CPU1")
		)
		(pad "2" smd circle
			(at 0.40005 0 270)
			(size 0 0)
			(layers "F.Cu" "F.Mask" "F.Paste")
			(net "GND")
		)
	)
	(footprint ""
		(layer "F.Cu")
		(at 216.065608 -404.823422)
		(property "Reference" "PC2183"
			(at 0 0 0)
			(layer "F.SilkS")
			(hide yes)
			(effects
				(font
					(size 1.27 1.27)
				)
			)
		)
		(property "Value" ""
			(at 0 0 0)
			(layer "F.Fab")
			(effects
				(font
					(size 1.27 1.27)
				)
			)
		)
		(duplicate_pad_numbers_are_jumpers no)
		(fp_line
			(start -0.7874 -0.4064)
			(end 0.7874 -0.4064)
			(stroke
				(width 0.1524)
				(type default)
			)
			(layer "F.SilkS")
		)
		(fp_line
			(start -0.7874 0.4064)
			(end -0.7874 -0.4064)
			(stroke
				(width 0.1524)
				(type default)
			)
			(layer "F.SilkS")
		)
		(fp_line
			(start 0.7874 -0.4064)
			(end 0.7874 0.4064)
			(stroke
				(width 0.1524)
				(type default)
			)
			(layer "F.SilkS")
		)
		(fp_line
			(start 0.7874 0.4064)
			(end -0.7874 0.4064)
			(stroke
				(width 0.1524)
				(type default)
			)
			(layer "F.SilkS")
		)
		(fp_line
			(start -0.67945 -0.305054)
			(end -0.12065 -0.305054)
			(stroke
				(width 0.1)
				(type default)
			)
			(layer "F.Fab")
		)
		(fp_line
			(start -0.67945 0.3048)
			(end -0.67945 -0.305054)
			(stroke
				(width 0.1)
				(type default)
			)
			(layer "F.Fab")
		)
		(fp_line
			(start -0.12065 -0.305054)
			(end -0.12065 -0.2794)
			(stroke
				(width 0.1)
				(type default)
			)
			(layer "F.Fab")
		)
		(fp_line
			(start -0.12065 -0.2794)
			(end 0.12065 -0.2794)
			(stroke
				(width 0.1)
				(type default)
			)
			(layer "F.Fab")
		)
		(fp_line
			(start -0.12065 0.2794)
			(end -0.12065 0.3048)
			(stroke
				(width 0.1)
				(type default)
			)
			(layer "F.Fab")
		)
		(fp_line
			(start -0.12065 0.3048)
			(end -0.67945 0.3048)
			(stroke
				(width 0.1)
				(type default)
			)
			(layer "F.Fab")
		)
		(fp_line
			(start 0.120396 0.2794)
			(end -0.12065 0.2794)
			(stroke
				(width 0.1)
				(type default)
			)
			(layer "F.Fab")
		)
		(fp_line
			(start 0.120396 0.3048)
			(end 0.120396 0.2794)
			(stroke
				(width 0.1)
				(type default)
			)
			(layer "F.Fab")
		)
		(fp_line
			(start 0.12065 -0.3048)
			(end 0.67945 -0.3048)
			(stroke
				(width 0.1)
				(type default)
			)
			(layer "F.Fab")
		)
		(fp_line
			(start 0.12065 -0.2794)
			(end 0.12065 -0.3048)
			(stroke
				(width 0.1)
				(type default)
			)
			(layer "F.Fab")
		)
		(fp_line
			(start 0.67945 -0.3048)
			(end 0.67945 0.3048)
			(stroke
				(width 0.1)
				(type default)
			)
			(layer "F.Fab")
		)
		(fp_line
			(start 0.67945 0.3048)
			(end 0.120396 0.3048)
			(stroke
				(width 0.1)
				(type default)
			)
			(layer "F.Fab")
		)
		(pad "1" smd circle
			(at -0.40005 0)
			(size 0 0)
			(layers "F.Cu" "F.Mask" "F.Paste")
			(net "HSC_ON")
		)
		(pad "2" smd circle
			(at 0.40005 0)
			(size 0 0)
			(layers "F.Cu" "F.Mask" "F.Paste")
			(net "AGND_HSC")
		)
	)
)
